(kicad_pcb
	(version 20260206)
	(generator "pcbnew")
	(generator_version "10.0")
	(general
		(thickness 1.6)
		(legacy_teardrops no)
	)
	(paper "A4")
	(title_block
		(title "panther-plus-userver — 13130-1b_20150205.brd")
		(comment 1 "Honey Badger (Wiwynn) / footprint 624 of 1509 (DIMM4), pads 9-15 of 210")
	)
	(layers
		(0 "F.Cu" signal "TOP")
		(4 "In1.Cu" signal "L2")
		(6 "In2.Cu" signal "L3")
		(8 "In3.Cu" signal "L4")
		(10 "In4.Cu" signal "L5")
		(12 "In5.Cu" signal "L6")
		(14 "In6.Cu" signal "L7")
		(16 "In7.Cu" signal "L8")
		(18 "In8.Cu" signal "L9")
		(20 "In9.Cu" signal "L10")
		(22 "In10.Cu" signal "L11")
		(2 "B.Cu" signal "BOTTOM")
		(9 "F.Adhes" user "F.Adhesive")
		(11 "B.Adhes" user "B.Adhesive")
		(13 "F.Paste" user "Package Geometry/Pastemask Top")
		(15 "B.Paste" user "Package Geometry/Pastemask Bottom")
		(5 "F.SilkS" user "Ref Des/Silkscreen Top")
		(7 "B.SilkS" user "Ref Des/Silkscreen Bottom")
		(1 "F.Mask" user "Board Geometry/Soldermask Top")
		(3 "B.Mask" user "Board Geometry/Soldermask Bottom")
		(17 "Dwgs.User" user "User.Drawings")
		(19 "Cmts.User" user "User.Comments")
		(21 "Eco1.User" user "User.Eco1")
		(23 "Eco2.User" user "User.Eco2")
		(25 "Edge.Cuts" user "Board Geometry/Outline")
		(27 "Margin" user)
		(31 "F.CrtYd" user "Package Geometry/Place Bound Top")
		(29 "B.CrtYd" user "Package Geometry/Place Bound Bottom")
		(35 "F.Fab" user "Ref Des/Assembly Top")
		(33 "B.Fab" user "Ref Des/Assembly Bottom")
	)
	(footprint ""
		(layer "F.Cu")
		(at 159.999934 -5.790692)
		(property "Reference" "DIMM4"
			(at 0 0 0)
			(layer "F.SilkS")
			(hide yes)
			(effects
				(font
					(size 1.27 1.27)
				)
			)
		)
		(property "Value" "DDR3-204P-174-COLAY-1-GP"
			(at -40.682164 -17.468088 0)
			(unlocked yes)
			(layer "F.Fab")
			(hide yes)
			(effects
				(font
					(size 1.016 1.016)
					(thickness 0.1524)
				)
			)
		)
		(property "Device Type" "AS0A626-H8SN-7H-COLAY-1"
			(at -40.682164 -18.992088 0)
			(unlocked yes)
			(layer "F.Fab")
			(hide yes)
			(effects
				(font
					(size 1.016 1.016)
					(thickness 0.1524)
				)
			)
		)
		(duplicate_pad_numbers_are_jumpers no)
		(pad "7" smd custom
			(at -29.85008 4.106672)
			(size 0.1143 0.1143)
			(layers "F.Cu" "F.Mask" "F.Paste")
			(net "M_B_DQ5")
			(options
				(clearance outline)
				(anchor circle)
			)
			(primitives
				(gr_poly
					(pts
						(xy 0 0.9017) (xy -0.03175 0.89916) (xy -0.0635 0.889) (xy -0.09144 0.87376) (xy -0.11684 0.85344)
						(xy -0.13716 0.82804) (xy -0.1524 0.8001) (xy -0.16256 0.76835) (xy -0.1651 0.7366) (xy -0.1651 0.11938)
						(xy -0.17272 0.11176) (xy -0.19812 0.0762) (xy -0.2032 0.06604) (xy -0.20701 0.05715) (xy -0.21209 0.04699)
						(xy -0.2159 0.03683) (xy -0.21844 0.02667) (xy -0.22225 0.01524) (xy -0.22352 0.00508) (xy -0.22606 -0.00508)
						(xy -0.22733 -0.01651) (xy -0.22733 -0.02667) (xy -0.2286 -0.0381) (xy -0.22733 -0.04953) (xy -0.22733 -0.05969)
						(xy -0.22606 -0.07112) (xy -0.22352 -0.08128) (xy -0.22225 -0.09144) (xy -0.21844 -0.10287) (xy -0.2159 -0.11303)
						(xy -0.21209 -0.12319) (xy -0.20701 -0.13335) (xy -0.2032 -0.14224) (xy -0.19812 -0.1524) (xy -0.17272 -0.18796)
						(xy -0.1651 -0.19558) (xy -0.1651 -0.7366) (xy -0.16256 -0.76835) (xy -0.1524 -0.8001) (xy -0.13716 -0.82804)
						(xy -0.11684 -0.85344) (xy -0.09144 -0.87376) (xy -0.0635 -0.889) (xy -0.03175 -0.89916) (xy 0 -0.9017)
						(xy 0.03175 -0.89916) (xy 0.0635 -0.889) (xy 0.09144 -0.87376) (xy 0.11684 -0.85344) (xy 0.13716 -0.82804)
						(xy 0.1524 -0.8001) (xy 0.16256 -0.76835) (xy 0.1651 -0.7366) (xy 0.1651 -0.19685) (xy 0.17272 -0.18923)
						(xy 0.17907 -0.18034) (xy 0.18669 -0.17145) (xy 0.19177 -0.16256) (xy 0.19812 -0.15367) (xy 0.20828 -0.13335)
						(xy 0.21971 -0.10287) (xy 0.22225 -0.09271) (xy 0.22479 -0.08128) (xy 0.22606 -0.07112) (xy 0.2286 -0.05969)
						(xy 0.2286 -0.01651) (xy 0.22606 -0.00508) (xy 0.22479 0.00508) (xy 0.22225 0.01651) (xy 0.21971 0.02667)
						(xy 0.20828 0.05715) (xy 0.19812 0.07747) (xy 0.19177 0.08636) (xy 0.18669 0.09525) (xy 0.17907 0.10414)
						(xy 0.17272 0.11303) (xy 0.1651 0.12065) (xy 0.1651 0.7366) (xy 0.16256 0.76835) (xy 0.1524 0.8001)
						(xy 0.13716 0.82804) (xy 0.11684 0.85344) (xy 0.09144 0.87376) (xy 0.0635 0.889) (xy 0.03175 0.89916)
					)
					(width 0)
					(fill yes)
				)
			)
		)
		(pad "8" smd custom
			(at -29.550106 -4.106672)
			(size 0.1143 0.1143)
			(layers "F.Cu" "F.Mask" "F.Paste")
			(net "GND")
			(options
				(clearance outline)
				(anchor circle)
			)
			(primitives
				(gr_poly
					(pts
						(xy 0 0.9017) (xy -0.03175 0.89916) (xy -0.0635 0.889) (xy -0.09144 0.87376) (xy -0.11684 0.85344)
						(xy -0.13716 0.82804) (xy -0.1524 0.8001) (xy -0.16256 0.76835) (xy -0.1651 0.7366) (xy -0.1651 0.19685)
						(xy -0.17272 0.18923) (xy -0.17907 0.18034) (xy -0.18669 0.17145) (xy -0.19177 0.16256) (xy -0.19812 0.15367)
						(xy -0.20828 0.13335) (xy -0.21971 0.10287) (xy -0.22225 0.09271) (xy -0.22479 0.08128) (xy -0.22606 0.07112)
						(xy -0.2286 0.05969) (xy -0.2286 0.01651) (xy -0.22606 0.00508) (xy -0.22479 -0.00508) (xy -0.22225 -0.01651)
						(xy -0.21971 -0.02667) (xy -0.20828 -0.05715) (xy -0.19812 -0.07747) (xy -0.19177 -0.08636) (xy -0.18669 -0.09525)
						(xy -0.17907 -0.10414) (xy -0.17272 -0.11303) (xy -0.1651 -0.12065) (xy -0.1651 -0.7366) (xy -0.16256 -0.76835)
						(xy -0.1524 -0.8001) (xy -0.13716 -0.82804) (xy -0.11684 -0.85344) (xy -0.09144 -0.87376) (xy -0.0635 -0.889)
						(xy -0.03175 -0.89916) (xy 0 -0.9017) (xy 0.03175 -0.89916) (xy 0.0635 -0.889) (xy 0.09144 -0.87376)
						(xy 0.11684 -0.85344) (xy 0.13716 -0.82804) (xy 0.1524 -0.8001) (xy 0.16256 -0.76835) (xy 0.1651 -0.7366)
						(xy 0.1651 -0.11938) (xy 0.17272 -0.11176) (xy 0.19812 -0.0762) (xy 0.2032 -0.06604) (xy 0.20701 -0.05715)
						(xy 0.21209 -0.04699) (xy 0.2159 -0.03683) (xy 0.21844 -0.02667) (xy 0.22225 -0.01524) (xy 0.22352 -0.00508)
						(xy 0.22606 0.00508) (xy 0.22733 0.01651) (xy 0.22733 0.02667) (xy 0.2286 0.0381) (xy 0.22733 0.04953)
						(xy 0.22733 0.05969) (xy 0.22606 0.07112) (xy 0.22352 0.08128) (xy 0.22225 0.09144) (xy 0.21844 0.10287)
						(xy 0.2159 0.11303) (xy 0.21209 0.12319) (xy 0.20701 0.13335) (xy 0.2032 0.14224) (xy 0.19812 0.1524)
						(xy 0.17272 0.18796) (xy 0.1651 0.19558) (xy 0.1651 0.7366) (xy 0.16256 0.76835) (xy 0.1524 0.8001)
						(xy 0.13716 0.82804) (xy 0.11684 0.85344) (xy 0.09144 0.87376) (xy 0.0635 0.889) (xy 0.03175 0.89916)
					)
					(width 0)
					(fill yes)
				)
			)
		)
		(pad "9" smd custom
			(at -29.249878 4.106672)
			(size 0.1143 0.1143)
			(layers "F.Cu" "F.Mask" "F.Paste")
			(net "GND")
			(options
				(clearance outline)
				(anchor circle)
			)
			(primitives
				(gr_poly
					(pts
						(xy 0 0.9017) (xy -0.03175 0.89916) (xy -0.0635 0.889) (xy -0.09144 0.87376) (xy -0.11684 0.85344)
						(xy -0.13716 0.82804) (xy -0.1524 0.8001) (xy -0.16256 0.76835) (xy -0.1651 0.7366) (xy -0.1651 -0.13462)
						(xy -0.17272 -0.14224) (xy -0.19812 -0.1778) (xy -0.2032 -0.18796) (xy -0.20701 -0.19685) (xy -0.21209 -0.20701)
						(xy -0.2159 -0.21717) (xy -0.21844 -0.22733) (xy -0.22225 -0.23876) (xy -0.22352 -0.24892) (xy -0.22606 -0.25908)
						(xy -0.22733 -0.27051) (xy -0.22733 -0.28067) (xy -0.2286 -0.2921) (xy -0.22733 -0.30353) (xy -0.22733 -0.31369)
						(xy -0.22606 -0.32512) (xy -0.22352 -0.33528) (xy -0.22225 -0.34544) (xy -0.21844 -0.35687) (xy -0.2159 -0.36703)
						(xy -0.21209 -0.37719) (xy -0.20701 -0.38735) (xy -0.2032 -0.39624) (xy -0.19812 -0.4064) (xy -0.17272 -0.44196)
						(xy -0.1651 -0.44958) (xy -0.1651 -0.7366) (xy -0.16256 -0.76835) (xy -0.1524 -0.8001) (xy -0.13716 -0.82804)
						(xy -0.11684 -0.85344) (xy -0.09144 -0.87376) (xy -0.0635 -0.889) (xy -0.03175 -0.89916) (xy 0 -0.9017)
						(xy 0.03175 -0.89916) (xy 0.0635 -0.889) (xy 0.09144 -0.87376) (xy 0.11684 -0.85344) (xy 0.13716 -0.82804)
						(xy 0.1524 -0.8001) (xy 0.16256 -0.76835) (xy 0.1651 -0.7366) (xy 0.1651 -0.44958) (xy 0.17272 -0.44196)
						(xy 0.19812 -0.4064) (xy 0.2032 -0.39624) (xy 0.20701 -0.38735) (xy 0.21209 -0.37719) (xy 0.2159 -0.36703)
						(xy 0.21844 -0.35687) (xy 0.22225 -0.34544) (xy 0.22352 -0.33528) (xy 0.22606 -0.32512) (xy 0.22733 -0.31369)
						(xy 0.22733 -0.30353) (xy 0.2286 -0.2921) (xy 0.22733 -0.28067) (xy 0.22733 -0.27051) (xy 0.22606 -0.25908)
						(xy 0.22352 -0.24892) (xy 0.22225 -0.23876) (xy 0.21844 -0.22733) (xy 0.2159 -0.21717) (xy 0.21209 -0.20701)
						(xy 0.20701 -0.19685) (xy 0.2032 -0.18796) (xy 0.19812 -0.1778) (xy 0.17272 -0.14224) (xy 0.1651 -0.13462)
						(xy 0.1651 0.7366) (xy 0.16256 0.76835) (xy 0.1524 0.8001) (xy 0.13716 0.82804) (xy 0.11684 0.85344)
						(xy 0.09144 0.87376) (xy 0.0635 0.889) (xy 0.03175 0.89916)
					)
					(width 0)
					(fill yes)
				)
			)
		)
		(pad "10" smd custom
			(at -28.949904 -4.106672)
			(size 0.1143 0.1143)
			(layers "F.Cu" "F.Mask" "F.Paste")
			(net "M_B_DQS_DN0")
			(options
				(clearance outline)
				(anchor circle)
			)
			(primitives
				(gr_poly
					(pts
						(xy 0 0.9017) (xy -0.03175 0.89916) (xy -0.0635 0.889) (xy -0.09144 0.87376) (xy -0.11684 0.85344)
						(xy -0.13716 0.82804) (xy -0.1524 0.8001) (xy -0.16256 0.76835) (xy -0.1651 0.7366) (xy -0.1651 0.44958)
						(xy -0.17272 0.44196) (xy -0.19812 0.4064) (xy -0.2032 0.39624) (xy -0.20701 0.38735) (xy -0.21209 0.37719)
						(xy -0.2159 0.36703) (xy -0.21844 0.35687) (xy -0.22225 0.34544) (xy -0.22352 0.33528) (xy -0.22606 0.32512)
						(xy -0.22733 0.31369) (xy -0.22733 0.30353) (xy -0.2286 0.2921) (xy -0.22733 0.28067) (xy -0.22733 0.27051)
						(xy -0.22606 0.25908) (xy -0.22352 0.24892) (xy -0.22225 0.23876) (xy -0.21844 0.22733) (xy -0.2159 0.21717)
						(xy -0.21209 0.20701) (xy -0.20701 0.19685) (xy -0.2032 0.18796) (xy -0.19812 0.1778) (xy -0.17272 0.14224)
						(xy -0.1651 0.13462) (xy -0.1651 -0.7366) (xy -0.16256 -0.76835) (xy -0.1524 -0.8001) (xy -0.13716 -0.82804)
						(xy -0.11684 -0.85344) (xy -0.09144 -0.87376) (xy -0.0635 -0.889) (xy -0.03175 -0.89916) (xy 0 -0.9017)
						(xy 0.03175 -0.89916) (xy 0.0635 -0.889) (xy 0.09144 -0.87376) (xy 0.11684 -0.85344) (xy 0.13716 -0.82804)
						(xy 0.1524 -0.8001) (xy 0.16256 -0.76835) (xy 0.1651 -0.7366) (xy 0.1651 0.13462) (xy 0.17272 0.14224)
						(xy 0.19812 0.1778) (xy 0.2032 0.18796) (xy 0.20701 0.19685) (xy 0.21209 0.20701) (xy 0.2159 0.21717)
						(xy 0.21844 0.22733) (xy 0.22225 0.23876) (xy 0.22352 0.24892) (xy 0.22606 0.25908) (xy 0.22733 0.27051)
						(xy 0.22733 0.28067) (xy 0.2286 0.2921) (xy 0.22733 0.30353) (xy 0.22733 0.31369) (xy 0.22606 0.32512)
						(xy 0.22352 0.33528) (xy 0.22225 0.34544) (xy 0.21844 0.35687) (xy 0.2159 0.36703) (xy 0.21209 0.37719)
						(xy 0.20701 0.38735) (xy 0.2032 0.39624) (xy 0.19812 0.4064) (xy 0.17272 0.44196) (xy 0.1651 0.44958)
						(xy 0.1651 0.7366) (xy 0.16256 0.76835) (xy 0.1524 0.8001) (xy 0.13716 0.82804) (xy 0.11684 0.85344)
						(xy 0.09144 0.87376) (xy 0.0635 0.889) (xy 0.03175 0.89916)
					)
					(width 0)
					(fill yes)
				)
			)
		)
		(pad "11" smd custom
			(at -28.64993 4.106672)
			(size 0.1143 0.1143)
			(layers "F.Cu" "F.Mask" "F.Paste")
			(net "GND")
			(options
				(clearance outline)
				(anchor circle)
			)
			(primitives
				(gr_poly
					(pts
						(xy 0 0.9017) (xy -0.03175 0.89916) (xy -0.0635 0.889) (xy -0.09144 0.87376) (xy -0.11684 0.85344)
						(xy -0.13716 0.82804) (xy -0.1524 0.8001) (xy -0.16256 0.76835) (xy -0.1651 0.7366) (xy -0.1651 0.11938)
						(xy -0.17272 0.11176) (xy -0.19812 0.0762) (xy -0.2032 0.06604) (xy -0.20701 0.05715) (xy -0.21209 0.04699)
						(xy -0.2159 0.03683) (xy -0.21844 0.02667) (xy -0.22225 0.01524) (xy -0.22352 0.00508) (xy -0.22606 -0.00508)
						(xy -0.22733 -0.01651) (xy -0.22733 -0.02667) (xy -0.2286 -0.0381) (xy -0.22733 -0.04953) (xy -0.22733 -0.05969)
						(xy -0.22606 -0.07112) (xy -0.22352 -0.08128) (xy -0.22225 -0.09144) (xy -0.21844 -0.10287) (xy -0.2159 -0.11303)
						(xy -0.21209 -0.12319) (xy -0.20701 -0.13335) (xy -0.2032 -0.14224) (xy -0.19812 -0.1524) (xy -0.17272 -0.18796)
						(xy -0.1651 -0.19558) (xy -0.1651 -0.7366) (xy -0.16256 -0.76835) (xy -0.1524 -0.8001) (xy -0.13716 -0.82804)
						(xy -0.11684 -0.85344) (xy -0.09144 -0.87376) (xy -0.0635 -0.889) (xy -0.03175 -0.89916) (xy 0 -0.9017)
						(xy 0.03175 -0.89916) (xy 0.0635 -0.889) (xy 0.09144 -0.87376) (xy 0.11684 -0.85344) (xy 0.13716 -0.82804)
						(xy 0.1524 -0.8001) (xy 0.16256 -0.76835) (xy 0.1651 -0.7366) (xy 0.1651 -0.19685) (xy 0.17272 -0.18923)
						(xy 0.17907 -0.18034) (xy 0.18669 -0.17145) (xy 0.19177 -0.16256) (xy 0.19812 -0.15367) (xy 0.20828 -0.13335)
						(xy 0.21971 -0.10287) (xy 0.22225 -0.09271) (xy 0.22479 -0.08128) (xy 0.22606 -0.07112) (xy 0.2286 -0.05969)
						(xy 0.2286 -0.01651) (xy 0.22606 -0.00508) (xy 0.22479 0.00508) (xy 0.22225 0.01651) (xy 0.21971 0.02667)
						(xy 0.20828 0.05715) (xy 0.19812 0.07747) (xy 0.19177 0.08636) (xy 0.18669 0.09525) (xy 0.17907 0.10414)
						(xy 0.17272 0.11303) (xy 0.1651 0.12065) (xy 0.1651 0.7366) (xy 0.16256 0.76835) (xy 0.1524 0.8001)
						(xy 0.13716 0.82804) (xy 0.11684 0.85344) (xy 0.09144 0.87376) (xy 0.0635 0.889) (xy 0.03175 0.89916)
					)
					(width 0)
					(fill yes)
				)
			)
		)
		(pad "12" smd custom
			(at -28.349956 -4.106672)
			(size 0.1143 0.1143)
			(layers "F.Cu" "F.Mask" "F.Paste")
			(net "M_B_DQS_DP0")
			(options
				(clearance outline)
				(anchor circle)
			)
			(primitives
				(gr_poly
					(pts
						(xy 0 0.9017) (xy -0.03175 0.89916) (xy -0.0635 0.889) (xy -0.09144 0.87376) (xy -0.11684 0.85344)
						(xy -0.13716 0.82804) (xy -0.1524 0.8001) (xy -0.16256 0.76835) (xy -0.1651 0.7366) (xy -0.1651 0.19685)
						(xy -0.17272 0.18923) (xy -0.17907 0.18034) (xy -0.18669 0.17145) (xy -0.19177 0.16256) (xy -0.19812 0.15367)
						(xy -0.20828 0.13335) (xy -0.21971 0.10287) (xy -0.22225 0.09271) (xy -0.22479 0.08128) (xy -0.22606 0.07112)
						(xy -0.2286 0.05969) (xy -0.2286 0.01651) (xy -0.22606 0.00508) (xy -0.22479 -0.00508) (xy -0.22225 -0.01651)
						(xy -0.21971 -0.02667) (xy -0.20828 -0.05715) (xy -0.19812 -0.07747) (xy -0.19177 -0.08636) (xy -0.18669 -0.09525)
						(xy -0.17907 -0.10414) (xy -0.17272 -0.11303) (xy -0.1651 -0.12065) (xy -0.1651 -0.7366) (xy -0.16256 -0.76835)
						(xy -0.1524 -0.8001) (xy -0.13716 -0.82804) (xy -0.11684 -0.85344) (xy -0.09144 -0.87376) (xy -0.0635 -0.889)
						(xy -0.03175 -0.89916) (xy 0 -0.9017) (xy 0.03175 -0.89916) (xy 0.0635 -0.889) (xy 0.09144 -0.87376)
						(xy 0.11684 -0.85344) (xy 0.13716 -0.82804) (xy 0.1524 -0.8001) (xy 0.16256 -0.76835) (xy 0.1651 -0.7366)
						(xy 0.1651 -0.11938) (xy 0.17272 -0.11176) (xy 0.19812 -0.0762) (xy 0.2032 -0.06604) (xy 0.20701 -0.05715)
						(xy 0.21209 -0.04699) (xy 0.2159 -0.03683) (xy 0.21844 -0.02667) (xy 0.22225 -0.01524) (xy 0.22352 -0.00508)
						(xy 0.22606 0.00508) (xy 0.22733 0.01651) (xy 0.22733 0.02667) (xy 0.2286 0.0381) (xy 0.22733 0.04953)
						(xy 0.22733 0.05969) (xy 0.22606 0.07112) (xy 0.22352 0.08128) (xy 0.22225 0.09144) (xy 0.21844 0.10287)
						(xy 0.2159 0.11303) (xy 0.21209 0.12319) (xy 0.20701 0.13335) (xy 0.2032 0.14224) (xy 0.19812 0.1524)
						(xy 0.17272 0.18796) (xy 0.1651 0.19558) (xy 0.1651 0.7366) (xy 0.16256 0.76835) (xy 0.1524 0.8001)
						(xy 0.13716 0.82804) (xy 0.11684 0.85344) (xy 0.09144 0.87376) (xy 0.0635 0.889) (xy 0.03175 0.89916)
					)
					(width 0)
					(fill yes)
				)
			)
		)
		(pad "13" smd custom
			(at -28.049982 4.106672)
			(size 0.1143 0.1143)
			(layers "F.Cu" "F.Mask" "F.Paste")
			(net "M_B_DQ6")
			(options
				(clearance outline)
				(anchor circle)
			)
			(primitives
				(gr_poly
					(pts
						(xy 0 0.9017) (xy -0.03175 0.89916) (xy -0.0635 0.889) (xy -0.09144 0.87376) (xy -0.11684 0.85344)
						(xy -0.13716 0.82804) (xy -0.1524 0.8001) (xy -0.16256 0.76835) (xy -0.1651 0.7366) (xy -0.1651 -0.13462)
						(xy -0.17272 -0.14224) (xy -0.19812 -0.1778) (xy -0.2032 -0.18796) (xy -0.20701 -0.19685) (xy -0.21209 -0.20701)
						(xy -0.2159 -0.21717) (xy -0.21844 -0.22733) (xy -0.22225 -0.23876) (xy -0.22352 -0.24892) (xy -0.22606 -0.25908)
						(xy -0.22733 -0.27051) (xy -0.22733 -0.28067) (xy -0.2286 -0.2921) (xy -0.22733 -0.30353) (xy -0.22733 -0.31369)
						(xy -0.22606 -0.32512) (xy -0.22352 -0.33528) (xy -0.22225 -0.34544) (xy -0.21844 -0.35687) (xy -0.2159 -0.36703)
						(xy -0.21209 -0.37719) (xy -0.20701 -0.38735) (xy -0.2032 -0.39624) (xy -0.19812 -0.4064) (xy -0.17272 -0.44196)
						(xy -0.1651 -0.44958) (xy -0.1651 -0.7366) (xy -0.16256 -0.76835) (xy -0.1524 -0.8001) (xy -0.13716 -0.82804)
						(xy -0.11684 -0.85344) (xy -0.09144 -0.87376) (xy -0.0635 -0.889) (xy -0.03175 -0.89916) (xy 0 -0.9017)
						(xy 0.03175 -0.89916) (xy 0.0635 -0.889) (xy 0.09144 -0.87376) (xy 0.11684 -0.85344) (xy 0.13716 -0.82804)
						(xy 0.1524 -0.8001) (xy 0.16256 -0.76835) (xy 0.1651 -0.7366) (xy 0.1651 -0.44958) (xy 0.17272 -0.44196)
						(xy 0.19812 -0.4064) (xy 0.2032 -0.39624) (xy 0.20701 -0.38735) (xy 0.21209 -0.37719) (xy 0.2159 -0.36703)
						(xy 0.21844 -0.35687) (xy 0.22225 -0.34544) (xy 0.22352 -0.33528) (xy 0.22606 -0.32512) (xy 0.22733 -0.31369)
						(xy 0.22733 -0.30353) (xy 0.2286 -0.2921) (xy 0.22733 -0.28067) (xy 0.22733 -0.27051) (xy 0.22606 -0.25908)
						(xy 0.22352 -0.24892) (xy 0.22225 -0.23876) (xy 0.21844 -0.22733) (xy 0.2159 -0.21717) (xy 0.21209 -0.20701)
						(xy 0.20701 -0.19685) (xy 0.2032 -0.18796) (xy 0.19812 -0.1778) (xy 0.17272 -0.14224) (xy 0.1651 -0.13462)
						(xy 0.1651 0.7366) (xy 0.16256 0.76835) (xy 0.1524 0.8001) (xy 0.13716 0.82804) (xy 0.11684 0.85344)
						(xy 0.09144 0.87376) (xy 0.0635 0.889) (xy 0.03175 0.89916)
					)
					(width 0)
					(fill yes)
				)
			)
		)
	)
)
